# BASEBOARD_FAB2 (Tioga Pass) — schematic netlist excerpt (pin names and nets, part order shuffled) for the footprints in the layout excerpt that follows; sources: Cadence DE-HDL packaged netlist, KiCad conversion of Wiwynn_Tioga_Pass_MB.brd

C2R7  CAP  0.22UF 16V 10% X7R  pkg 0402  page 106 : A = P3E_CPU0_PE3_OCP_TXN<6> ; B = P3E_OCP_CPU0_PE3_C_TXN<6>
R25W85  RES  22.1 1.0% CHIP  pkg 0402  page 147 : A = RMII_BMC_OCP_TXEN_R ; B = RMII_BMC_OCP_TXEN
C7G35  SC1U10V2KX-4-GP  10%  pkg SMD-BCG6  page 216 : \1\ = P5V_STBY ; \2\ = GND

(kicad_pcb
	(version 20260206)
	(generator "pcbnew")
	(generator_version "10.0")
	(general
		(thickness 1.6)
		(legacy_teardrops no)
	)
	(paper "A4")
	(title_block
		(title "Wiwynn_Tioga_Pass_MB.brd")
		(comment 1 "Tioga Pass / footprints 4763-4765 of 4770")
	)
	(layers
		(0 "F.Cu" signal "TOP")
		(4 "In1.Cu" signal "L2GND")
		(6 "In2.Cu" signal "L3")
		(8 "In3.Cu" signal "L4GND")
		(10 "In4.Cu" signal "L5")
		(12 "In5.Cu" signal "L6GND")
		(14 "In6.Cu" signal "L7VCC")
		(16 "In7.Cu" signal "L8VCC")
		(18 "In8.Cu" signal "L9GND")
		(20 "In9.Cu" signal "L10")
		(22 "In10.Cu" signal "L11GND")
		(24 "In11.Cu" signal "L12")
		(26 "In12.Cu" signal "L13GND")
		(2 "B.Cu" signal "BOTTOM")
		(9 "F.Adhes" user "F.Adhesive")
		(11 "B.Adhes" user "B.Adhesive")
		(13 "F.Paste" user "Package Geometry/Pastemask Top")
		(15 "B.Paste" user "Package Geometry/Pastemask Bottom")
		(5 "F.SilkS" user "Ref Des/Silkscreen Top")
		(7 "B.SilkS" user "Ref Des/Silkscreen Bottom")
		(1 "F.Mask" user "Board Geometry/Soldermask Top")
		(3 "B.Mask" user "Board Geometry/Soldermask Bottom")
		(17 "Dwgs.User" user "User.Drawings")
		(19 "Cmts.User" user "User.Comments")
		(21 "Eco1.User" user "User.Eco1")
		(23 "Eco2.User" user "User.Eco2")
		(25 "Edge.Cuts" user "Board Geometry/Outline")
		(27 "Margin" user)
		(31 "F.CrtYd" user "Package Geometry/Place Bound Top")
		(29 "B.CrtYd" user "Package Geometry/Place Bound Bottom")
		(35 "F.Fab" user "Ref Des/Assembly Top")
		(33 "B.Fab" user "Ref Des/Assembly Bottom")
	)
	(footprint ""
		(layer "B.Cu")
		(at 407.654506 -32.661352 180)
		(property "Reference" "R25W85"
			(at 0.8382 -0.67818 180)
			(unlocked yes)
			(layer "B.SilkS")
			(effects
				(font
					(size 0.4064 0.254)
					(thickness 0.1524)
				)
				(justify left mirror)
			)
		)
		(property "Value" ""
			(at 0 0 0)
			(layer "B.Fab")
			(effects
				(font
					(size 1.27 1.27)
				)
				(justify mirror)
			)
		)
		(duplicate_pad_numbers_are_jumpers no)
		(fp_poly
			(pts
				(xy 0.2794 -0.1016) (xy -0.2794 -0.1016) (xy -0.2794 0.9906) (xy 0.2794 0.9906)
			)
			(stroke
				(width 0)
				(type default)
			)
			(fill no)
			(layer "B.CrtYd")
		)
		(fp_line
			(start 0.2794 0.9906)
			(end -0.2794 0.9906)
			(stroke
				(width 0.1)
				(type default)
			)
			(layer "B.Fab")
		)
		(fp_line
			(start 0.2794 -0.1016)
			(end 0.2794 0.9906)
			(stroke
				(width 0.1)
				(type default)
			)
			(layer "B.Fab")
		)
		(fp_line
			(start -0.2794 0.9906)
			(end -0.2794 -0.1016)
			(stroke
				(width 0.1)
				(type default)
			)
			(layer "B.Fab")
		)
		(fp_line
			(start -0.2794 -0.1016)
			(end 0.2794 -0.1016)
			(stroke
				(width 0.1)
				(type default)
			)
			(layer "B.Fab")
		)
		(pad "1" smd rect
			(at 0 0)
			(size 0.508 0.508)
			(layers "B.Cu" "B.Mask" "B.Paste")
			(net "RMII_BMC_OCP_TXEN_R")
		)
		(pad "2" smd rect
			(at 0 0.889)
			(size 0.508 0.508)
			(layers "B.Cu" "B.Mask" "B.Paste")
			(net "RMII_BMC_OCP_TXEN")
		)
		(zone
			(layer "B.Cu")
			(hatch none 0.5)
			(connect_pads
				(clearance 0)
			)
			(min_thickness 0.25)
			(keepout
				(tracks not_allowed)
				(vias allowed)
				(pads allowed)
				(copperpour not_allowed)
				(footprints allowed)
			)
			(placement
				(enabled no)
				(sheetname "")
			)
			(fill
				(thermal_gap 0.5)
				(thermal_bridge_width 0.5)
				(island_removal_mode 0)
			)
			(polygon
				(pts
					(xy 407.400506 -33.296352) (xy 407.908506 -33.296352) (xy 407.908506 -32.915352) (xy 407.400506 -32.915352)
				)
			)
		)
		(zone
			(layer "B.Cu")
			(hatch none 0.5)
			(connect_pads
				(clearance 0)
			)
			(min_thickness 0.25)
			(keepout
				(tracks allowed)
				(vias not_allowed)
				(pads allowed)
				(copperpour not_allowed)
				(footprints allowed)
			)
			(placement
				(enabled no)
				(sheetname "")
			)
			(fill
				(thermal_gap 0.5)
				(thermal_bridge_width 0.5)
				(island_removal_mode 0)
			)
			(polygon
				(pts
					(xy 407.400506 -32.915352) (xy 407.908506 -32.915352) (xy 407.908506 -33.296352) (xy 407.400506 -33.296352)
				)
			)
		)
	)
	(footprint ""
		(layer "B.Cu")
		(at 444.649606 -52.342034)
		(property "Reference" "C2R7"
			(at 0 0 0)
			(layer "B.SilkS")
			(hide yes)
			(effects
				(font
					(size 1.27 1.27)
				)
				(justify mirror)
			)
		)
		(property "Value" ""
			(at 0 0 0)
			(layer "B.Fab")
			(effects
				(font
					(size 1.27 1.27)
				)
				(justify mirror)
			)
		)
		(duplicate_pad_numbers_are_jumpers no)
		(fp_poly
			(pts
				(xy -0.3048 -0.1016) (xy -0.3048 0.9906) (xy 0.3048 0.9906) (xy 0.3048 -0.1016)
			)
			(stroke
				(width 0)
				(type default)
			)
			(fill no)
			(layer "B.CrtYd")
		)
		(fp_line
			(start -0.3048 -0.1016)
			(end 0.3048 -0.1016)
			(stroke
				(width 0.1)
				(type default)
			)
			(layer "B.Fab")
		)
		(fp_line
			(start -0.3048 0.9906)
			(end -0.3048 -0.1016)
			(stroke
				(width 0.1)
				(type default)
			)
			(layer "B.Fab")
		)
		(fp_line
			(start 0.3048 -0.1016)
			(end 0.3048 0.9906)
			(stroke
				(width 0.1)
				(type default)
			)
			(layer "B.Fab")
		)
		(fp_line
			(start 0.3048 0.9906)
			(end -0.3048 0.9906)
			(stroke
				(width 0.1)
				(type default)
			)
			(layer "B.Fab")
		)
		(pad "1" smd rect
			(at 0 0 180)
			(size 0.508 0.508)
			(layers "B.Cu" "B.Mask" "B.Paste")
			(net "P3E_CPU0_PE3_OCP_TXN<6>")
		)
		(pad "2" smd rect
			(at 0 0.889 180)
			(size 0.508 0.508)
			(layers "B.Cu" "B.Mask" "B.Paste")
			(net "P3E_OCP_CPU0_PE3_C_TXN<6>")
		)
		(zone
			(layer "B.Cu")
			(hatch none 0.5)
			(connect_pads
				(clearance 0)
			)
			(min_thickness 0.25)
			(keepout
				(tracks allowed)
				(vias not_allowed)
				(pads allowed)
				(copperpour not_allowed)
				(footprints allowed)
			)
			(placement
				(enabled no)
				(sheetname "")
			)
			(fill
				(thermal_gap 0.5)
				(thermal_bridge_width 0.5)
				(island_removal_mode 0)
			)
			(polygon
				(pts
					(xy 444.903606 -52.088034) (xy 444.395606 -52.088034) (xy 444.395606 -51.707034) (xy 444.903606 -51.707034)
				)
			)
		)
		(zone
			(layer "B.Cu")
			(hatch none 0.5)
			(connect_pads
				(clearance 0)
			)
			(min_thickness 0.25)
			(keepout
				(tracks not_allowed)
				(vias allowed)
				(pads allowed)
				(copperpour not_allowed)
				(footprints allowed)
			)
			(placement
				(enabled no)
				(sheetname "")
			)
			(fill
				(thermal_gap 0.5)
				(thermal_bridge_width 0.5)
				(island_removal_mode 0)
			)
			(polygon
				(pts
					(xy 444.903606 -51.707034) (xy 444.395606 -51.707034) (xy 444.395606 -52.088034) (xy 444.903606 -52.088034)
				)
			)
		)
	)
	(footprint ""
		(layer "B.Cu")
		(at 346.72524 -10.28446 -90)
		(property "Reference" "C7G35"
			(at 0 0 90)
			(layer "B.SilkS")
			(hide yes)
			(effects
				(font
					(size 1.27 1.27)
				)
				(justify mirror)
			)
		)
		(property "Value" "*"
			(at -1.1811 -2.8194 270)
			(unlocked yes)
			(layer "B.Fab")
			(hide yes)
			(effects
				(font
					(size 1.27 1.016)
					(thickness 0.1524)
				)
				(justify mirror)
			)
		)
		(property "Device Type" "SC1U10V2KX-4-GP_SMD-BCG6-SC1U1A"
			(at -1.1811 -4.3434 270)
			(unlocked yes)
			(layer "B.Fab")
			(hide yes)
			(effects
				(font
					(size 1.27 1.016)
					(thickness 0.1524)
				)
				(justify mirror)
			)
		)
		(duplicate_pad_numbers_are_jumpers no)
		(fp_rect
			(start 0.4318 0.9525)
			(end -0.4318 -0.9525)
			(stroke
				(width 0)
				(type default)
			)
			(fill no)
			(layer "B.CrtYd")
		)
		(fp_rect
			(start 0.4318 0.9525)
			(end -0.4318 -0.9525)
			(stroke
				(width 0)
				(type default)
			)
			(fill no)
			(layer "B.Fab")
		)
		(pad "1" smd custom
			(at 0 -0.4445 90)
			(size 0.1524 0.1524)
			(layers "B.Cu" "B.Mask" "B.Paste")
			(net "P5V_STBY")
			(options
				(clearance outline)
				(anchor circle)
			)
			(primitives
				(gr_poly
					(pts
						(arc
							(start 0.3048 0.2032)
							(mid 0.275042 0.275042)
							(end 0.2032 0.3048)
						)
						(arc
							(start -0.2032 0.3048)
							(mid -0.275042 0.275042)
							(end -0.3048 0.2032)
						)
						(arc
							(start -0.3048 -0.2032)
							(mid -0.275042 -0.275042)
							(end -0.2032 -0.3048)
						)
						(arc
							(start 0.2032 -0.3048)
							(mid 0.275042 -0.275042)
							(end 0.3048 -0.2032)
						)
					)
					(width 0)
					(fill yes)
				)
			)
		)
		(pad "2" smd custom
			(at 0 0.4445 90)
			(size 0.1524 0.1524)
			(layers "B.Cu" "B.Mask" "B.Paste")
			(net "GND")
			(options
				(clearance outline)
				(anchor circle)
			)
			(primitives
				(gr_poly
					(pts
						(arc
							(start 0.3048 0.2032)
							(mid 0.275042 0.275042)
							(end 0.2032 0.3048)
						)
						(arc
							(start -0.2032 0.3048)
							(mid -0.275042 0.275042)
							(end -0.3048 0.2032)
						)
						(arc
							(start -0.3048 -0.2032)
							(mid -0.275042 -0.275042)
							(end -0.2032 -0.3048)
						)
						(arc
							(start 0.2032 -0.3048)
							(mid 0.275042 -0.275042)
							(end 0.3048 -0.2032)
						)
					)
					(width 0)
					(fill yes)
				)
			)
		)
	)
)
